(kicad_pcb
	(version 20260206)
	(generator "pcbnew")
	(generator_version "10.0")
	(general
		(thickness 1.6)
		(legacy_teardrops no)
	)
	(paper "A4")
	(title_block
		(title "01162023_DA0F0TEBIF0_F0T_Expander_BD_F_brd_V02_OCP.brd")
		(comment 1 "Grand Teton / footprints 5212-5219 of 9728")
	)
	(layers
		(0 "F.Cu" signal "TOP")
		(4 "In1.Cu" signal "GND")
		(6 "In2.Cu" signal "VCC")
		(8 "In3.Cu" signal "VCC1")
		(10 "In4.Cu" signal "GND1")
		(12 "In5.Cu" signal "IN1")
		(14 "In6.Cu" signal "GND2")
		(16 "In7.Cu" signal "IN2")
		(18 "In8.Cu" signal "GND3")
		(20 "In9.Cu" signal "IN3")
		(22 "In10.Cu" signal "GND4")
		(24 "In11.Cu" signal "IN4")
		(26 "In12.Cu" signal "GND5")
		(28 "In13.Cu" signal "IN5")
		(30 "In14.Cu" signal "GND6")
		(32 "In15.Cu" signal "IN6")
		(34 "In16.Cu" signal "GND7")
		(2 "B.Cu" signal "BOTTOM")
		(9 "F.Adhes" user "F.Adhesive")
		(11 "B.Adhes" user "B.Adhesive")
		(13 "F.Paste" user "Package Geometry/Pastemask Top")
		(15 "B.Paste" user "Package Geometry/Pastemask Bottom")
		(5 "F.SilkS" user "Ref Des/Silkscreen Top")
		(7 "B.SilkS" user "Ref Des/Silkscreen Bottom")
		(1 "F.Mask" user "Board Geometry/Soldermask Top")
		(3 "B.Mask" user "Board Geometry/Soldermask Bottom")
		(17 "Dwgs.User" user "User.Drawings")
		(19 "Cmts.User" user "User.Comments")
		(21 "Eco1.User" user "User.Eco1")
		(23 "Eco2.User" user "User.Eco2")
		(25 "Edge.Cuts" user "Board Geometry/Outline")
		(27 "Margin" user)
		(31 "F.CrtYd" user "Package Geometry/Place Bound Top")
		(29 "B.CrtYd" user "Package Geometry/Place Bound Bottom")
		(35 "F.Fab" user "Ref Des/Assembly Top")
		(33 "B.Fab" user "Ref Des/Assembly Bottom")
	)
	(footprint ""
		(layer "F.Cu")
		(at 242.730528 -144.067276 180)
		(property "Reference" "PC800"
			(at 0 0 180)
			(layer "F.SilkS")
			(hide yes)
			(effects
				(font
					(size 1.27 1.27)
				)
			)
		)
		(property "Value" ""
			(at 0 0 180)
			(layer "F.Fab")
			(effects
				(font
					(size 1.27 1.27)
				)
			)
		)
		(duplicate_pad_numbers_are_jumpers no)
		(fp_line
			(start 1.524 0.762)
			(end -1.524 0.762)
			(stroke
				(width 0.1524)
				(type default)
			)
			(layer "F.SilkS")
		)
		(fp_line
			(start 1.524 -0.762)
			(end 1.524 0.762)
			(stroke
				(width 0.1524)
				(type default)
			)
			(layer "F.SilkS")
		)
		(fp_line
			(start -1.524 0.762)
			(end -1.524 -0.762)
			(stroke
				(width 0.1524)
				(type default)
			)
			(layer "F.SilkS")
		)
		(fp_line
			(start -1.524 -0.762)
			(end 1.524 -0.762)
			(stroke
				(width 0.1524)
				(type default)
			)
			(layer "F.SilkS")
		)
		(fp_line
			(start 1.1049 0.724916)
			(end 1.1049 -0.724916)
			(stroke
				(width 0.1)
				(type default)
			)
			(layer "F.Fab")
		)
		(fp_line
			(start 1.1049 -0.724916)
			(end -1.1049 -0.724916)
			(stroke
				(width 0.1)
				(type default)
			)
			(layer "F.Fab")
		)
		(fp_line
			(start -1.1049 0.724916)
			(end 1.1049 0.724916)
			(stroke
				(width 0.1)
				(type default)
			)
			(layer "F.Fab")
		)
		(fp_line
			(start -1.1049 -0.724916)
			(end -1.1049 0.724916)
			(stroke
				(width 0.1)
				(type default)
			)
			(layer "F.Fab")
		)
		(pad "1" smd rect
			(at -0.889 0)
			(size 1.016 1.27)
			(layers "F.Cu" "F.Mask" "F.Paste")
			(net "P12V_NIC4_R")
		)
		(pad "2" smd rect
			(at 0.889 0)
			(size 1.016 1.27)
			(layers "F.Cu" "F.Mask" "F.Paste")
			(net "GND")
		)
	)
	(footprint ""
		(layer "F.Cu")
		(at 71.257922 -72.766682 90)
		(property "Reference" "PC651"
			(at 0 0 90)
			(layer "F.SilkS")
			(hide yes)
			(effects
				(font
					(size 1.27 1.27)
				)
			)
		)
		(property "Value" ""
			(at 0 0 90)
			(layer "F.Fab")
			(effects
				(font
					(size 1.27 1.27)
				)
			)
		)
		(duplicate_pad_numbers_are_jumpers no)
		(fp_line
			(start 0.7874 -0.4064)
			(end 0.7874 0.4064)
			(stroke
				(width 0.1524)
				(type default)
			)
			(layer "F.SilkS")
		)
		(fp_line
			(start -0.7874 -0.4064)
			(end 0.7874 -0.4064)
			(stroke
				(width 0.1524)
				(type default)
			)
			(layer "F.SilkS")
		)
		(fp_line
			(start 0.7874 0.4064)
			(end -0.7874 0.4064)
			(stroke
				(width 0.1524)
				(type default)
			)
			(layer "F.SilkS")
		)
		(fp_line
			(start -0.7874 0.4064)
			(end -0.7874 -0.4064)
			(stroke
				(width 0.1524)
				(type default)
			)
			(layer "F.SilkS")
		)
		(fp_line
			(start -0.12065 -0.305054)
			(end -0.12065 -0.2794)
			(stroke
				(width 0.1)
				(type default)
			)
			(layer "F.Fab")
		)
		(fp_line
			(start -0.67945 -0.305054)
			(end -0.12065 -0.305054)
			(stroke
				(width 0.1)
				(type default)
			)
			(layer "F.Fab")
		)
		(fp_line
			(start 0.67945 -0.3048)
			(end 0.67945 0.3048)
			(stroke
				(width 0.1)
				(type default)
			)
			(layer "F.Fab")
		)
		(fp_line
			(start 0.12065 -0.3048)
			(end 0.67945 -0.3048)
			(stroke
				(width 0.1)
				(type default)
			)
			(layer "F.Fab")
		)
		(fp_line
			(start 0.12065 -0.2794)
			(end 0.12065 -0.3048)
			(stroke
				(width 0.1)
				(type default)
			)
			(layer "F.Fab")
		)
		(fp_line
			(start -0.12065 -0.2794)
			(end 0.12065 -0.2794)
			(stroke
				(width 0.1)
				(type default)
			)
			(layer "F.Fab")
		)
		(fp_line
			(start 0.120396 0.2794)
			(end -0.12065 0.2794)
			(stroke
				(width 0.1)
				(type default)
			)
			(layer "F.Fab")
		)
		(fp_line
			(start -0.12065 0.2794)
			(end -0.12065 0.3048)
			(stroke
				(width 0.1)
				(type default)
			)
			(layer "F.Fab")
		)
		(fp_line
			(start 0.67945 0.3048)
			(end 0.120396 0.3048)
			(stroke
				(width 0.1)
				(type default)
			)
			(layer "F.Fab")
		)
		(fp_line
			(start 0.120396 0.3048)
			(end 0.120396 0.2794)
			(stroke
				(width 0.1)
				(type default)
			)
			(layer "F.Fab")
		)
		(fp_line
			(start -0.12065 0.3048)
			(end -0.67945 0.3048)
			(stroke
				(width 0.1)
				(type default)
			)
			(layer "F.Fab")
		)
		(fp_line
			(start -0.67945 0.3048)
			(end -0.67945 -0.305054)
			(stroke
				(width 0.1)
				(type default)
			)
			(layer "F.Fab")
		)
		(pad "1" smd circle
			(at -0.40005 0 90)
			(size 0 0)
			(layers "F.Cu" "F.Mask" "F.Paste")
			(net "P12V_SSD2_CO_MODE")
		)
		(pad "2" smd circle
			(at 0.40005 0 90)
			(size 0 0)
			(layers "F.Cu" "F.Mask" "F.Paste")
			(net "GND")
		)
	)
	(footprint ""
		(layer "F.Cu")
		(at 222.053658 -184.053226)
		(property "Reference" "U362"
			(at -1.524 -1.87833 0)
			(unlocked yes)
			(layer "F.SilkS")
			(effects
				(font
					(size 0.7874 0.5842)
					(thickness 0.1524)
				)
				(justify left)
			)
		)
		(property "Value" ""
			(at 0 0 0)
			(layer "F.Fab")
			(effects
				(font
					(size 1.27 1.27)
				)
			)
		)
		(duplicate_pad_numbers_are_jumpers no)
		(fp_line
			(start -1.4986 -1.100074)
			(end 1.4986 -1.100074)
			(stroke
				(width 0.1524)
				(type default)
			)
			(layer "F.SilkS")
		)
		(fp_line
			(start -1.4986 1.100074)
			(end -1.4986 -1.100074)
			(stroke
				(width 0.1524)
				(type default)
			)
			(layer "F.SilkS")
		)
		(fp_line
			(start 1.4986 -1.100074)
			(end 1.4986 1.100074)
			(stroke
				(width 0.1524)
				(type default)
			)
			(layer "F.SilkS")
		)
		(fp_line
			(start 1.4986 1.100074)
			(end -1.4986 1.100074)
			(stroke
				(width 0.1524)
				(type default)
			)
			(layer "F.SilkS")
		)
		(fp_poly
			(pts
				(xy -2.323338 -1.214628) (xy -1.881632 -1.656334) (xy -1.72212 -1.032764)
			)
			(stroke
				(width 0)
				(type default)
			)
			(fill yes)
			(layer "F.SilkS")
		)
		(fp_line
			(start -0.67437 -1.100074)
			(end 0.67437 -1.100074)
			(stroke
				(width 0.1)
				(type default)
			)
			(layer "F.Fab")
		)
		(fp_line
			(start -0.67437 1.100074)
			(end -0.67437 -1.100074)
			(stroke
				(width 0.1)
				(type default)
			)
			(layer "F.Fab")
		)
		(fp_line
			(start 0.67437 -1.100074)
			(end 0.67437 1.100074)
			(stroke
				(width 0.1)
				(type default)
			)
			(layer "F.Fab")
		)
		(fp_line
			(start 0.67437 1.100074)
			(end -0.67437 1.100074)
			(stroke
				(width 0.1)
				(type default)
			)
			(layer "F.Fab")
		)
		(fp_poly
			(pts
				(xy -2.20472 -0.338328) (xy -2.20472 -0.963168) (xy -1.651 -0.635)
			)
			(stroke
				(width 0)
				(type default)
			)
			(fill yes)
			(layer "F.Fab")
		)
		(pad "1" smd rect
			(at -0.889 -0.649986)
			(size 1.016 0.381)
			(layers "F.Cu" "F.Mask" "F.Paste")
			(net "Net_8959")
		)
		(pad "2" smd rect
			(at -0.889 0)
			(size 1.016 0.381)
			(layers "F.Cu" "F.Mask" "F.Paste")
			(net "RST_BIC_BUF_RSMRST_N")
		)
		(pad "3" smd rect
			(at -0.889 0.649986)
			(size 1.016 0.381)
			(layers "F.Cu" "F.Mask" "F.Paste")
			(net "GND")
		)
		(pad "4" smd rect
			(at 0.889 0.649986)
			(size 1.016 0.381)
			(layers "F.Cu" "F.Mask" "F.Paste")
			(net "RST_BIC_BUF_RSMRST_N_BUF")
		)
		(pad "5" smd rect
			(at 0.889 -0.649986)
			(size 1.016 0.381)
			(layers "F.Cu" "F.Mask" "F.Paste")
			(net "P3V3_AUX")
		)
	)
	(footprint ""
		(layer "F.Cu")
		(at 80.915002 -350.098614 90)
		(property "Reference" "C110"
			(at 0 0 90)
			(layer "F.SilkS")
			(hide yes)
			(effects
				(font
					(size 1.27 1.27)
				)
			)
		)
		(property "Value" ""
			(at 0 0 90)
			(layer "F.Fab")
			(effects
				(font
					(size 1.27 1.27)
				)
			)
		)
		(duplicate_pad_numbers_are_jumpers no)
		(fp_line
			(start 0.299974 -0.150114)
			(end 0.299974 0.150114)
			(stroke
				(width 0.1)
				(type default)
			)
			(layer "F.Fab")
		)
		(fp_line
			(start -0.299974 -0.150114)
			(end 0.299974 -0.150114)
			(stroke
				(width 0.1)
				(type default)
			)
			(layer "F.Fab")
		)
		(fp_line
			(start 0.299974 0.150114)
			(end -0.299974 0.150114)
			(stroke
				(width 0.1)
				(type default)
			)
			(layer "F.Fab")
		)
		(fp_line
			(start -0.299974 0.150114)
			(end -0.299974 -0.150114)
			(stroke
				(width 0.1)
				(type default)
			)
			(layer "F.Fab")
		)
		(pad "1" smd rect
			(at -0.2667 0 90)
			(size 0.3048 0.381)
			(layers "F.Cu" "F.Mask" "F.Paste")
			(net "P5E_PEX0_STN5_TX_DN<89>")
		)
		(pad "2" smd rect
			(at 0.2667 0 90)
			(size 0.3048 0.381)
			(layers "F.Cu" "F.Mask" "F.Paste")
			(net "P5E_PEX0_STN5_TX_C_DN<89>")
		)
	)
	(footprint ""
		(layer "F.Cu")
		(at 441.273692 -343.952322 90)
		(property "Reference" "C797"
			(at 0 0 90)
			(layer "F.SilkS")
			(hide yes)
			(effects
				(font
					(size 1.27 1.27)
				)
			)
		)
		(property "Value" ""
			(at 0 0 90)
			(layer "F.Fab")
			(effects
				(font
					(size 1.27 1.27)
				)
			)
		)
		(duplicate_pad_numbers_are_jumpers no)
		(fp_line
			(start 0.299974 -0.150114)
			(end 0.299974 0.150114)
			(stroke
				(width 0.1)
				(type default)
			)
			(layer "F.Fab")
		)
		(fp_line
			(start -0.299974 -0.150114)
			(end 0.299974 -0.150114)
			(stroke
				(width 0.1)
				(type default)
			)
			(layer "F.Fab")
		)
		(fp_line
			(start 0.299974 0.150114)
			(end -0.299974 0.150114)
			(stroke
				(width 0.1)
				(type default)
			)
			(layer "F.Fab")
		)
		(fp_line
			(start -0.299974 0.150114)
			(end -0.299974 -0.150114)
			(stroke
				(width 0.1)
				(type default)
			)
			(layer "F.Fab")
		)
		(pad "1" smd rect
			(at -0.2667 0 90)
			(size 0.3048 0.381)
			(layers "F.Cu" "F.Mask" "F.Paste")
			(net "P5E_PEX3_STN7_TX_DN<126>")
		)
		(pad "2" smd rect
			(at 0.2667 0 90)
			(size 0.3048 0.381)
			(layers "F.Cu" "F.Mask" "F.Paste")
			(net "P5E_PEX3_STN7_TX_C_DN<126>")
		)
	)
	(footprint ""
		(layer "F.Cu")
		(at 99.28987 -72.766682 90)
		(property "Reference" "PR6912"
			(at 0 0 90)
			(layer "F.SilkS")
			(hide yes)
			(effects
				(font
					(size 1.27 1.27)
				)
			)
		)
		(property "Value" ""
			(at 0 0 90)
			(layer "F.Fab")
			(effects
				(font
					(size 1.27 1.27)
				)
			)
		)
		(duplicate_pad_numbers_are_jumpers no)
		(fp_line
			(start 0.7874 -0.4064)
			(end 0.7874 0.4064)
			(stroke
				(width 0.1524)
				(type default)
			)
			(layer "F.SilkS")
		)
		(fp_line
			(start -0.7874 -0.4064)
			(end 0.7874 -0.4064)
			(stroke
				(width 0.1524)
				(type default)
			)
			(layer "F.SilkS")
		)
		(fp_line
			(start 0.7874 0.4064)
			(end -0.7874 0.4064)
			(stroke
				(width 0.1524)
				(type default)
			)
			(layer "F.SilkS")
		)
		(fp_line
			(start -0.7874 0.4064)
			(end -0.7874 -0.4064)
			(stroke
				(width 0.1524)
				(type default)
			)
			(layer "F.SilkS")
		)
		(fp_line
			(start -0.12065 -0.305054)
			(end -0.12065 -0.2794)
			(stroke
				(width 0.1)
				(type default)
			)
			(layer "F.Fab")
		)
		(fp_line
			(start -0.67945 -0.305054)
			(end -0.12065 -0.305054)
			(stroke
				(width 0.1)
				(type default)
			)
			(layer "F.Fab")
		)
		(fp_line
			(start 0.67945 -0.3048)
			(end 0.67945 0.3048)
			(stroke
				(width 0.1)
				(type default)
			)
			(layer "F.Fab")
		)
		(fp_line
			(start 0.12065 -0.3048)
			(end 0.67945 -0.3048)
			(stroke
				(width 0.1)
				(type default)
			)
			(layer "F.Fab")
		)
		(fp_line
			(start 0.12065 -0.2794)
			(end 0.12065 -0.3048)
			(stroke
				(width 0.1)
				(type default)
			)
			(layer "F.Fab")
		)
		(fp_line
			(start -0.12065 -0.2794)
			(end 0.12065 -0.2794)
			(stroke
				(width 0.1)
				(type default)
			)
			(layer "F.Fab")
		)
		(fp_line
			(start 0.120396 0.2794)
			(end -0.12065 0.2794)
			(stroke
				(width 0.1)
				(type default)
			)
			(layer "F.Fab")
		)
		(fp_line
			(start -0.12065 0.2794)
			(end -0.12065 0.3048)
			(stroke
				(width 0.1)
				(type default)
			)
			(layer "F.Fab")
		)
		(fp_line
			(start 0.67945 0.3048)
			(end 0.120396 0.3048)
			(stroke
				(width 0.1)
				(type default)
			)
			(layer "F.Fab")
		)
		(fp_line
			(start 0.120396 0.3048)
			(end 0.120396 0.2794)
			(stroke
				(width 0.1)
				(type default)
			)
			(layer "F.Fab")
		)
		(fp_line
			(start -0.12065 0.3048)
			(end -0.67945 0.3048)
			(stroke
				(width 0.1)
				(type default)
			)
			(layer "F.Fab")
		)
		(fp_line
			(start -0.67945 0.3048)
			(end -0.67945 -0.305054)
			(stroke
				(width 0.1)
				(type default)
			)
			(layer "F.Fab")
		)
		(pad "1" smd circle
			(at -0.40005 0 90)
			(size 0 0)
			(layers "F.Cu" "F.Mask" "F.Paste")
			(net "P12V_SSD3_CO_ILIMIT")
		)
		(pad "2" smd circle
			(at 0.40005 0 90)
			(size 0 0)
			(layers "F.Cu" "F.Mask" "F.Paste")
			(net "GND")
		)
	)
	(footprint ""
		(layer "F.Cu")
		(at 143.091154 -255.359662)
		(property "Reference" "C3239"
			(at 0 0 0)
			(layer "F.SilkS")
			(hide yes)
			(effects
				(font
					(size 1.27 1.27)
				)
			)
		)
		(property "Value" ""
			(at 0 0 0)
			(layer "F.Fab")
			(effects
				(font
					(size 1.27 1.27)
				)
			)
		)
		(duplicate_pad_numbers_are_jumpers no)
		(fp_line
			(start -1.2954 -0.5842)
			(end 1.2954 -0.5842)
			(stroke
				(width 0.1524)
				(type default)
			)
			(layer "F.SilkS")
		)
		(fp_line
			(start -1.2954 0.5842)
			(end -1.2954 -0.5842)
			(stroke
				(width 0.1524)
				(type default)
			)
			(layer "F.SilkS")
		)
		(fp_line
			(start 1.2954 -0.5842)
			(end 1.2954 0.5842)
			(stroke
				(width 0.1524)
				(type default)
			)
			(layer "F.SilkS")
		)
		(fp_line
			(start 1.2954 0.5842)
			(end -1.2954 0.5842)
			(stroke
				(width 0.1524)
				(type default)
			)
			(layer "F.SilkS")
		)
		(fp_line
			(start -1.1938 -0.4064)
			(end -0.8636 -0.4064)
			(stroke
				(width 0.1)
				(type default)
			)
			(layer "F.Fab")
		)
		(fp_line
			(start -1.1938 0.4064)
			(end -1.1938 -0.4064)
			(stroke
				(width 0.1)
				(type default)
			)
			(layer "F.Fab")
		)
		(fp_line
			(start -0.8636 -0.4572)
			(end 0.8636 -0.4572)
			(stroke
				(width 0.1)
				(type default)
			)
			(layer "F.Fab")
		)
		(fp_line
			(start -0.8636 -0.4064)
			(end -0.8636 -0.4572)
			(stroke
				(width 0.1)
				(type default)
			)
			(layer "F.Fab")
		)
		(fp_line
			(start -0.8636 0.4064)
			(end -1.1938 0.4064)
			(stroke
				(width 0.1)
				(type default)
			)
			(layer "F.Fab")
		)
		(fp_line
			(start -0.8636 0.4572)
			(end -0.8636 0.4064)
			(stroke
				(width 0.1)
				(type default)
			)
			(layer "F.Fab")
		)
		(fp_line
			(start 0.8636 -0.4572)
			(end 0.8636 -0.4064)
			(stroke
				(width 0.1)
				(type default)
			)
			(layer "F.Fab")
		)
		(fp_line
			(start 0.8636 -0.4064)
			(end 1.1938 -0.4064)
			(stroke
				(width 0.1)
				(type default)
			)
			(layer "F.Fab")
		)
		(fp_line
			(start 0.8636 0.4064)
			(end 0.8636 0.4572)
			(stroke
				(width 0.1)
				(type default)
			)
			(layer "F.Fab")
		)
		(fp_line
			(start 0.8636 0.4572)
			(end -0.8636 0.4572)
			(stroke
				(width 0.1)
				(type default)
			)
			(layer "F.Fab")
		)
		(fp_line
			(start 1.1938 -0.4064)
			(end 1.1938 0.4064)
			(stroke
				(width 0.1)
				(type default)
			)
			(layer "F.Fab")
		)
		(fp_line
			(start 1.1938 0.4064)
			(end 0.8636 0.4064)
			(stroke
				(width 0.1)
				(type default)
			)
			(layer "F.Fab")
		)
		(pad "1" smd rect
			(at -0.7366 0 270)
			(size 0.7112 0.8128)
			(layers "F.Cu" "F.Mask" "F.Paste")
			(net "P1V8_PLL0_PEX1")
		)
		(pad "2" smd rect
			(at 0.7366 0 270)
			(size 0.7112 0.8128)
			(layers "F.Cu" "F.Mask" "F.Paste")
			(net "GND")
		)
	)
	(footprint ""
		(layer "F.Cu")
		(at 124.220732 -26.666444 -90)
		(property "Reference" "R4061"
			(at 0 0 270)
			(layer "F.SilkS")
			(hide yes)
			(effects
				(font
					(size 1.27 1.27)
				)
			)
		)
		(property "Value" ""
			(at 0 0 270)
			(layer "F.Fab")
			(effects
				(font
					(size 1.27 1.27)
				)
			)
		)
		(duplicate_pad_numbers_are_jumpers no)
		(fp_line
			(start -0.7874 0.4064)
			(end -0.7874 -0.4064)
			(stroke
				(width 0.1524)
				(type default)
			)
			(layer "F.SilkS")
		)
		(fp_line
			(start 0.7874 0.4064)
			(end -0.7874 0.4064)
			(stroke
				(width 0.1524)
				(type default)
			)
			(layer "F.SilkS")
		)
		(fp_line
			(start -0.7874 -0.4064)
			(end 0.7874 -0.4064)
			(stroke
				(width 0.1524)
				(type default)
			)
			(layer "F.SilkS")
		)
		(fp_line
			(start 0.7874 -0.4064)
			(end 0.7874 0.4064)
			(stroke
				(width 0.1524)
				(type default)
			)
			(layer "F.SilkS")
		)
		(fp_line
			(start -0.67945 0.3048)
			(end -0.67945 -0.305054)
			(stroke
				(width 0.1)
				(type default)
			)
			(layer "F.Fab")
		)
		(fp_line
			(start -0.12065 0.3048)
			(end -0.67945 0.3048)
			(stroke
				(width 0.1)
				(type default)
			)
			(layer "F.Fab")
		)
		(fp_line
			(start 0.120396 0.3048)
			(end 0.120396 0.2794)
			(stroke
				(width 0.1)
				(type default)
			)
			(layer "F.Fab")
		)
		(fp_line
			(start 0.67945 0.3048)
			(end 0.120396 0.3048)
			(stroke
				(width 0.1)
				(type default)
			)
			(layer "F.Fab")
		)
		(fp_line
			(start -0.12065 0.2794)
			(end -0.12065 0.3048)
			(stroke
				(width 0.1)
				(type default)
			)
			(layer "F.Fab")
		)
		(fp_line
			(start 0.120396 0.2794)
			(end -0.12065 0.2794)
			(stroke
				(width 0.1)
				(type default)
			)
			(layer "F.Fab")
		)
		(fp_line
			(start -0.12065 -0.2794)
			(end 0.12065 -0.2794)
			(stroke
				(width 0.1)
				(type default)
			)
			(layer "F.Fab")
		)
		(fp_line
			(start 0.12065 -0.2794)
			(end 0.12065 -0.3048)
			(stroke
				(width 0.1)
				(type default)
			)
			(layer "F.Fab")
		)
		(fp_line
			(start 0.12065 -0.3048)
			(end 0.67945 -0.3048)
			(stroke
				(width 0.1)
				(type default)
			)
			(layer "F.Fab")
		)
		(fp_line
			(start 0.67945 -0.3048)
			(end 0.67945 0.3048)
			(stroke
				(width 0.1)
				(type default)
			)
			(layer "F.Fab")
		)
		(fp_line
			(start -0.67945 -0.305054)
			(end -0.12065 -0.305054)
			(stroke
				(width 0.1)
				(type default)
			)
			(layer "F.Fab")
		)
		(fp_line
			(start -0.12065 -0.305054)
			(end -0.12065 -0.2794)
			(stroke
				(width 0.1)
				(type default)
			)
			(layer "F.Fab")
		)
		(pad "1" smd circle
			(at -0.40005 0 270)
			(size 0 0)
			(layers "F.Cu" "F.Mask" "F.Paste")
			(net "PRSNT_SSD4_R_N")
		)
		(pad "2" smd circle
			(at 0.40005 0 270)
			(size 0 0)
			(layers "F.Cu" "F.Mask" "F.Paste")
			(net "PRSNT_SSD4_N")
		)
	)
)
